# S9S_MB_2U (Grand Teton) — schematic netlist excerpt (pin names and nets, part order shuffled) for the footprints in the layout excerpt that follows; sources: Cadence DE-HDL packaged netlist, KiCad conversion of 03242023_DA0F0TMBIJ0_F0T_Motherboard_J_brd_V01_OCP.brd

X11  TP_TDR_4P_FTS  TP_TDR_4P_DIP EMPTY  pkg TH  page 309
  S1  = TDR_DIFF_85_IN4_DN
  P1  = T1_GND
  P2  = T1_GND
  S2  = TDR_DIFF_85_IN4_DP

C394  Q_CAP  47UF 4V 20% X6S  pkg C0805  page 76 : A = PVCCIN_CPU0 ; B = GND

(kicad_pcb
	(version 20260206)
	(generator "pcbnew")
	(generator_version "10.0")
	(general
		(thickness 1.6)
		(legacy_teardrops no)
	)
	(paper "A4")
	(title_block
		(title "03242023_DA0F0TMBIJ0_F0T_Motherboard_J_brd_V01_OCP.brd")
		(comment 1 "Grand Teton / footprints 5668-5669 of 6105")
	)
	(layers
		(0 "F.Cu" signal "TOP")
		(4 "In1.Cu" signal "GND")
		(6 "In2.Cu" signal "IN1")
		(8 "In3.Cu" signal "GND1")
		(10 "In4.Cu" signal "IN2")
		(12 "In5.Cu" signal "GND2")
		(14 "In6.Cu" signal "IN3")
		(16 "In7.Cu" signal "GND3")
		(18 "In8.Cu" signal "VCC")
		(20 "In9.Cu" signal "VCC1")
		(22 "In10.Cu" signal "GND4")
		(24 "In11.Cu" signal "IN4")
		(26 "In12.Cu" signal "GND5")
		(28 "In13.Cu" signal "IN5")
		(30 "In14.Cu" signal "GND6")
		(32 "In15.Cu" signal "IN6")
		(34 "In16.Cu" signal "GND7")
		(2 "B.Cu" signal "BOTTOM")
		(9 "F.Adhes" user "F.Adhesive")
		(11 "B.Adhes" user "B.Adhesive")
		(13 "F.Paste" user "Package Geometry/Pastemask Top")
		(15 "B.Paste" user "Package Geometry/Pastemask Bottom")
		(5 "F.SilkS" user "Ref Des/Silkscreen Top")
		(7 "B.SilkS" user "Ref Des/Silkscreen Bottom")
		(1 "F.Mask" user "Board Geometry/Soldermask Top")
		(3 "B.Mask" user "Board Geometry/Soldermask Bottom")
		(17 "Dwgs.User" user "User.Drawings")
		(19 "Cmts.User" user "User.Comments")
		(21 "Eco1.User" user "User.Eco1")
		(23 "Eco2.User" user "User.Eco2")
		(25 "Edge.Cuts" user "Board Geometry/Outline")
		(27 "Margin" user)
		(31 "F.CrtYd" user "Package Geometry/Place Bound Top")
		(29 "B.CrtYd" user "Package Geometry/Place Bound Bottom")
		(35 "F.Fab" user "Ref Des/Assembly Top")
		(33 "B.Fab" user "Ref Des/Assembly Bottom")
	)
	(footprint ""
		(layer "B.Cu")
		(at 522.584426 -303.621948 -90)
		(property "Reference" "X11"
			(at 3.493008 2.66319 270)
			(unlocked yes)
			(layer "B.SilkS")
			(effects
				(font
					(size 0.7874 0.5842)
					(thickness 0.1524)
				)
				(justify left mirror)
			)
		)
		(property "Value" ""
			(at 0 0 90)
			(layer "B.Fab")
			(effects
				(font
					(size 1.27 1.27)
				)
				(justify mirror)
			)
		)
		(property "Device Type" "TP_TDR_4P_FTS_TH-TP_TDR_4P_DIPA"
			(at -1.30175 1.27 180)
			(unlocked yes)
			(layer "B.Fab")
			(hide yes)
			(effects
				(font
					(size 0.635 0.4064)
					(thickness 0.1524)
				)
				(justify mirror)
			)
		)
		(property "User Part Number" "N_A"
			(at -1.30175 1.27 180)
			(unlocked yes)
			(layer "Cmts.User")
			(hide yes)
			(effects
				(font
					(size 0.635 0.4064)
					(thickness 0.1524)
				)
				(justify mirror)
			)
		)
		(duplicate_pad_numbers_are_jumpers no)
		(fp_line
			(start -2.54 3.81)
			(end -2.54 3.6703)
			(stroke
				(width 0.1524)
				(type default)
			)
			(layer "B.SilkS")
		)
		(fp_line
			(start 0 3.81)
			(end -2.54 3.81)
			(stroke
				(width 0.1524)
				(type default)
			)
			(layer "B.SilkS")
		)
		(fp_line
			(start 0 3.175)
			(end 0 3.81)
			(stroke
				(width 0.1524)
				(type default)
			)
			(layer "B.SilkS")
		)
		(fp_line
			(start -2.54 1.4097)
			(end -2.54 1.1303)
			(stroke
				(width 0.1524)
				(type default)
			)
			(layer "B.SilkS")
		)
		(fp_line
			(start 0 0.635)
			(end 0 1.905)
			(stroke
				(width 0.1524)
				(type default)
			)
			(layer "B.SilkS")
		)
		(fp_line
			(start -2.54 -1.1303)
			(end -2.54 -1.27)
			(stroke
				(width 0.1524)
				(type default)
			)
			(layer "B.SilkS")
		)
		(fp_line
			(start -2.54 -1.27)
			(end 0 -1.27)
			(stroke
				(width 0.1524)
				(type default)
			)
			(layer "B.SilkS")
		)
		(fp_line
			(start 0 -1.27)
			(end 0 -0.635)
			(stroke
				(width 0.1524)
				(type default)
			)
			(layer "B.SilkS")
		)
		(fp_poly
			(pts
				(xy 2.812034 -0.762) (xy 2.812034 0.762) (xy 1.288034 0)
			)
			(stroke
				(width 0)
				(type default)
			)
			(fill yes)
			(layer "B.SilkS")
		)
		(fp_line
			(start -2.54 3.81)
			(end -2.54 -1.27)
			(stroke
				(width 0.1)
				(type default)
			)
			(layer "B.Fab")
		)
		(fp_line
			(start 0 3.81)
			(end -2.54 3.81)
			(stroke
				(width 0.1)
				(type default)
			)
			(layer "B.Fab")
		)
		(fp_line
			(start -2.54 -1.27)
			(end 0 -1.27)
			(stroke
				(width 0.1)
				(type default)
			)
			(layer "B.Fab")
		)
		(fp_line
			(start 0 -1.27)
			(end 0 3.81)
			(stroke
				(width 0.1)
				(type default)
			)
			(layer "B.Fab")
		)
		(fp_poly
			(pts
				(xy 0.761746 0) (xy 2.285746 -0.762) (xy 2.285746 0.762)
			)
			(stroke
				(width 0)
				(type default)
			)
			(fill yes)
			(layer "B.Fab")
		)
		(pad "1" thru_hole circle
			(at 0 0 90)
			(size 1.0033 1.0033)
			(drill 0.249936)
			(layers "*.Cu" "*.Mask")
			(remove_unused_layers no)
			(net "TDR_DIFF_85_IN4_DN")
			(clearance 0.10795)
			(padstack
				(mode front_inner_back)
				(layer "Inner"
					(shape circle)
					(size 0.8001 0.8001)
					(clearance 0.1524)
				)
				(layer "B.Cu"
					(shape circle)
					(size 1.0033 1.0033)
					(thermal_gap 0.10795)
					(clearance 0.10795)
				)
			)
		)
		(pad "2" thru_hole circle
			(at -2.54 0 90)
			(size 1.9939 1.9939)
			(drill 0.249936)
			(layers "*.Cu" "*.Mask")
			(remove_unused_layers no)
			(net "T1_GND")
			(clearance 0.10795)
			(padstack
				(mode front_inner_back)
				(layer "Inner"
					(shape circle)
					(size 0.8001 0.8001)
					(clearance 0.1524)
				)
				(layer "B.Cu"
					(shape circle)
					(size 1.9939 1.9939)
					(thermal_gap 0.10795)
					(clearance 0.10795)
				)
			)
		)
		(pad "3" thru_hole circle
			(at -2.54 2.54 90)
			(size 1.9939 1.9939)
			(drill 0.249936)
			(layers "*.Cu" "*.Mask")
			(remove_unused_layers no)
			(net "T1_GND")
			(clearance 0.10795)
			(padstack
				(mode front_inner_back)
				(layer "Inner"
					(shape circle)
					(size 0.8001 0.8001)
					(clearance 0.1524)
				)
				(layer "B.Cu"
					(shape circle)
					(size 1.9939 1.9939)
					(thermal_gap 0.10795)
					(clearance 0.10795)
				)
			)
		)
		(pad "4" thru_hole circle
			(at 0 2.54 90)
			(size 1.0033 1.0033)
			(drill 0.249936)
			(layers "*.Cu" "*.Mask")
			(remove_unused_layers no)
			(net "TDR_DIFF_85_IN4_DP")
			(clearance 0.10795)
			(padstack
				(mode front_inner_back)
				(layer "Inner"
					(shape circle)
					(size 0.8001 0.8001)
					(clearance 0.1524)
				)
				(layer "B.Cu"
					(shape circle)
					(size 1.0033 1.0033)
					(thermal_gap 0.10795)
					(clearance 0.10795)
				)
			)
		)
	)
	(footprint ""
		(layer "B.Cu")
		(at 363.135418 -296.054526 180)
		(property "Reference" "C394"
			(at 0 0 0)
			(layer "B.SilkS")
			(hide yes)
			(effects
				(font
					(size 1.27 1.27)
				)
				(justify mirror)
			)
		)
		(property "Value" ""
			(at 0 0 0)
			(layer "B.Fab")
			(effects
				(font
					(size 1.27 1.27)
				)
				(justify mirror)
			)
		)
		(duplicate_pad_numbers_are_jumpers no)
		(fp_line
			(start 1.524 0.762)
			(end 1.524 -0.762)
			(stroke
				(width 0.1524)
				(type default)
			)
			(layer "B.SilkS")
		)
		(fp_line
			(start 1.524 -0.762)
			(end -1.524 -0.762)
			(stroke
				(width 0.1524)
				(type default)
			)
			(layer "B.SilkS")
		)
		(fp_line
			(start -1.524 0.762)
			(end 1.524 0.762)
			(stroke
				(width 0.1524)
				(type default)
			)
			(layer "B.SilkS")
		)
		(fp_line
			(start -1.524 -0.762)
			(end -1.524 0.762)
			(stroke
				(width 0.1524)
				(type default)
			)
			(layer "B.SilkS")
		)
		(fp_line
			(start 1.1049 0.724916)
			(end -1.1049 0.724916)
			(stroke
				(width 0.1)
				(type default)
			)
			(layer "B.Fab")
		)
		(fp_line
			(start 1.1049 -0.724916)
			(end 1.1049 0.724916)
			(stroke
				(width 0.1)
				(type default)
			)
			(layer "B.Fab")
		)
		(fp_line
			(start -1.1049 0.724916)
			(end -1.1049 -0.724916)
			(stroke
				(width 0.1)
				(type default)
			)
			(layer "B.Fab")
		)
		(fp_line
			(start -1.1049 -0.724916)
			(end 1.1049 -0.724916)
			(stroke
				(width 0.1)
				(type default)
			)
			(layer "B.Fab")
		)
		(pad "1" smd rect
			(at 0.889 0 180)
			(size 1.016 1.27)
			(layers "B.Cu" "B.Mask" "B.Paste")
			(net "PVCCIN_CPU0")
		)
		(pad "2" smd rect
			(at -0.889 0 180)
			(size 1.016 1.27)
			(layers "B.Cu" "B.Mask" "B.Paste")
			(net "GND")
		)
	)
)
